# SCM (Grand Teton) — schematic netlist excerpt (pin names and nets, part order shuffled) for the footprints in the layout excerpt that follows; sources: Cadence DE-HDL packaged netlist, KiCad conversion of 12092022_DA0F0TMDCD0_F0T_Management_Board_D_brd_V3_OCP.brd

R464  Q_RES  10K 1% CHIP  pkg 0402LF  page 46 : A = P3V3_AUX ; B = FM_TPM_PRSNT_0_N
R333  Q_RES  120 1% CHIP  pkg 0402LF  page 20 : A = GND ; B = M_BMC_DDR4_MA<7>

(kicad_pcb
	(version 20260206)
	(generator "pcbnew")
	(generator_version "10.0")
	(general
		(thickness 1.6)
		(legacy_teardrops no)
	)
	(paper "A4")
	(title_block
		(title "12092022_DA0F0TMDCD0_F0T_Management_Board_D_brd_V3_OCP.brd")
		(comment 1 "Grand Teton / footprints 208-209 of 1440")
	)
	(layers
		(0 "F.Cu" signal "TOP")
		(4 "In1.Cu" signal "GND")
		(6 "In2.Cu" signal "IN1")
		(8 "In3.Cu" signal "GND1")
		(10 "In4.Cu" signal "IN2")
		(12 "In5.Cu" signal "VCC")
		(14 "In6.Cu" signal "VCC1")
		(16 "In7.Cu" signal "IN3")
		(18 "In8.Cu" signal "GND2")
		(20 "In9.Cu" signal "IN4")
		(22 "In10.Cu" signal "GND3")
		(2 "B.Cu" signal "BOTTOM")
		(9 "F.Adhes" user "F.Adhesive")
		(11 "B.Adhes" user "B.Adhesive")
		(13 "F.Paste" user "Package Geometry/Pastemask Top")
		(15 "B.Paste" user "Package Geometry/Pastemask Bottom")
		(5 "F.SilkS" user "Ref Des/Silkscreen Top")
		(7 "B.SilkS" user "Ref Des/Silkscreen Bottom")
		(1 "F.Mask" user "Board Geometry/Soldermask Top")
		(3 "B.Mask" user "Board Geometry/Soldermask Bottom")
		(17 "Dwgs.User" user "User.Drawings")
		(19 "Cmts.User" user "User.Comments")
		(21 "Eco1.User" user "User.Eco1")
		(23 "Eco2.User" user "User.Eco2")
		(25 "Edge.Cuts" user "Board Geometry/Outline")
		(27 "Margin" user)
		(31 "F.CrtYd" user "Package Geometry/Place Bound Top")
		(29 "B.CrtYd" user "Package Geometry/Place Bound Bottom")
		(35 "F.Fab" user "Ref Des/Assembly Top")
		(33 "B.Fab" user "Ref Des/Assembly Bottom")
	)
	(footprint ""
		(layer "F.Cu")
		(at 85.29955 -44.427394 180)
		(property "Reference" "R333"
			(at 0 0 180)
			(layer "F.SilkS")
			(hide yes)
			(effects
				(font
					(size 1.27 1.27)
				)
			)
		)
		(property "Value" ""
			(at 0 0 180)
			(layer "F.Fab")
			(effects
				(font
					(size 1.27 1.27)
				)
			)
		)
		(duplicate_pad_numbers_are_jumpers no)
		(fp_line
			(start 0.7874 0.4064)
			(end -0.7874 0.4064)
			(stroke
				(width 0.1524)
				(type default)
			)
			(layer "F.SilkS")
		)
		(fp_line
			(start 0.7874 -0.4064)
			(end 0.7874 0.4064)
			(stroke
				(width 0.1524)
				(type default)
			)
			(layer "F.SilkS")
		)
		(fp_line
			(start -0.7874 0.4064)
			(end -0.7874 -0.4064)
			(stroke
				(width 0.1524)
				(type default)
			)
			(layer "F.SilkS")
		)
		(fp_line
			(start -0.7874 -0.4064)
			(end 0.7874 -0.4064)
			(stroke
				(width 0.1524)
				(type default)
			)
			(layer "F.SilkS")
		)
		(fp_line
			(start 0.67945 0.3048)
			(end 0.120396 0.3048)
			(stroke
				(width 0.1)
				(type default)
			)
			(layer "F.Fab")
		)
		(fp_line
			(start 0.67945 -0.3048)
			(end 0.67945 0.3048)
			(stroke
				(width 0.1)
				(type default)
			)
			(layer "F.Fab")
		)
		(fp_line
			(start 0.12065 -0.2794)
			(end 0.12065 -0.3048)
			(stroke
				(width 0.1)
				(type default)
			)
			(layer "F.Fab")
		)
		(fp_line
			(start 0.12065 -0.3048)
			(end 0.67945 -0.3048)
			(stroke
				(width 0.1)
				(type default)
			)
			(layer "F.Fab")
		)
		(fp_line
			(start 0.120396 0.3048)
			(end 0.120396 0.2794)
			(stroke
				(width 0.1)
				(type default)
			)
			(layer "F.Fab")
		)
		(fp_line
			(start 0.120396 0.2794)
			(end -0.12065 0.2794)
			(stroke
				(width 0.1)
				(type default)
			)
			(layer "F.Fab")
		)
		(fp_line
			(start -0.12065 0.3048)
			(end -0.67945 0.3048)
			(stroke
				(width 0.1)
				(type default)
			)
			(layer "F.Fab")
		)
		(fp_line
			(start -0.12065 0.2794)
			(end -0.12065 0.3048)
			(stroke
				(width 0.1)
				(type default)
			)
			(layer "F.Fab")
		)
		(fp_line
			(start -0.12065 -0.2794)
			(end 0.12065 -0.2794)
			(stroke
				(width 0.1)
				(type default)
			)
			(layer "F.Fab")
		)
		(fp_line
			(start -0.12065 -0.305054)
			(end -0.12065 -0.2794)
			(stroke
				(width 0.1)
				(type default)
			)
			(layer "F.Fab")
		)
		(fp_line
			(start -0.67945 0.3048)
			(end -0.67945 -0.305054)
			(stroke
				(width 0.1)
				(type default)
			)
			(layer "F.Fab")
		)
		(fp_line
			(start -0.67945 -0.305054)
			(end -0.12065 -0.305054)
			(stroke
				(width 0.1)
				(type default)
			)
			(layer "F.Fab")
		)
		(pad "1" smd circle
			(at -0.40005 0 180)
			(size 0 0)
			(layers "F.Cu" "F.Mask" "F.Paste")
			(net "GND")
		)
		(pad "2" smd circle
			(at 0.40005 0 180)
			(size 0 0)
			(layers "F.Cu" "F.Mask" "F.Paste")
			(net "M_BMC_DDR4_MA<7>")
		)
	)
	(footprint ""
		(layer "F.Cu")
		(at 57.18556 -94.5896)
		(property "Reference" "R464"
			(at 0 0 0)
			(layer "F.SilkS")
			(hide yes)
			(effects
				(font
					(size 1.27 1.27)
				)
			)
		)
		(property "Value" ""
			(at 0 0 0)
			(layer "F.Fab")
			(effects
				(font
					(size 1.27 1.27)
				)
			)
		)
		(duplicate_pad_numbers_are_jumpers no)
		(fp_line
			(start -0.7874 -0.4064)
			(end 0.7874 -0.4064)
			(stroke
				(width 0.1524)
				(type default)
			)
			(layer "F.SilkS")
		)
		(fp_line
			(start -0.7874 0.4064)
			(end -0.7874 -0.4064)
			(stroke
				(width 0.1524)
				(type default)
			)
			(layer "F.SilkS")
		)
		(fp_line
			(start 0.7874 -0.4064)
			(end 0.7874 0.4064)
			(stroke
				(width 0.1524)
				(type default)
			)
			(layer "F.SilkS")
		)
		(fp_line
			(start 0.7874 0.4064)
			(end -0.7874 0.4064)
			(stroke
				(width 0.1524)
				(type default)
			)
			(layer "F.SilkS")
		)
		(fp_line
			(start -0.67945 -0.305054)
			(end -0.12065 -0.305054)
			(stroke
				(width 0.1)
				(type default)
			)
			(layer "F.Fab")
		)
		(fp_line
			(start -0.67945 0.3048)
			(end -0.67945 -0.305054)
			(stroke
				(width 0.1)
				(type default)
			)
			(layer "F.Fab")
		)
		(fp_line
			(start -0.12065 -0.305054)
			(end -0.12065 -0.2794)
			(stroke
				(width 0.1)
				(type default)
			)
			(layer "F.Fab")
		)
		(fp_line
			(start -0.12065 -0.2794)
			(end 0.12065 -0.2794)
			(stroke
				(width 0.1)
				(type default)
			)
			(layer "F.Fab")
		)
		(fp_line
			(start -0.12065 0.2794)
			(end -0.12065 0.3048)
			(stroke
				(width 0.1)
				(type default)
			)
			(layer "F.Fab")
		)
		(fp_line
			(start -0.12065 0.3048)
			(end -0.67945 0.3048)
			(stroke
				(width 0.1)
				(type default)
			)
			(layer "F.Fab")
		)
		(fp_line
			(start 0.120396 0.2794)
			(end -0.12065 0.2794)
			(stroke
				(width 0.1)
				(type default)
			)
			(layer "F.Fab")
		)
		(fp_line
			(start 0.120396 0.3048)
			(end 0.120396 0.2794)
			(stroke
				(width 0.1)
				(type default)
			)
			(layer "F.Fab")
		)
		(fp_line
			(start 0.12065 -0.3048)
			(end 0.67945 -0.3048)
			(stroke
				(width 0.1)
				(type default)
			)
			(layer "F.Fab")
		)
		(fp_line
			(start 0.12065 -0.2794)
			(end 0.12065 -0.3048)
			(stroke
				(width 0.1)
				(type default)
			)
			(layer "F.Fab")
		)
		(fp_line
			(start 0.67945 -0.3048)
			(end 0.67945 0.3048)
			(stroke
				(width 0.1)
				(type default)
			)
			(layer "F.Fab")
		)
		(fp_line
			(start 0.67945 0.3048)
			(end 0.120396 0.3048)
			(stroke
				(width 0.1)
				(type default)
			)
			(layer "F.Fab")
		)
		(pad "1" smd circle
			(at -0.40005 0)
			(size 0 0)
			(layers "F.Cu" "F.Mask" "F.Paste")
			(net "P3V3_AUX")
		)
		(pad "2" smd circle
			(at 0.40005 0)
			(size 0 0)
			(layers "F.Cu" "F.Mask" "F.Paste")
			(net "FM_TPM_PRSNT_0_N")
		)
	)
)
